FILE_TYPE = MACRO_DRAWING;
SET COLOR_WIRE YELLOW;
SET COLOR_PROP ORANGE;
SET COLOR_DOT WHITE;
SET COLOR_ARC YELLOW;
SET COLOR_BODY GREEN;
SET COLOR_NOTE PURPLE;
SET PROP_DISPLAY VALUE;
SET PAGE_NUMBER P18;
SET PATH_NUMBER P0;
FORCEADD QUANTA_TITLE_BLOCK_C..1
(17500 -1625);
FORCEPROP 0 LAST CDS_CON_LAST_MODIFIED Fri Aug 25 17:25:38 2023
J 0
(15615 -1610);
DISPLAY INVISIBLE (15615 -1610);
FORCEPROP 2 LAST Q_DEPT 
J 1
(13737 -1576);
DISPLAY 1.957447 (13737 -1576);
PAINT GREEN (13737 -1576);
FORCEPROP 1 LAST CUSTOM_TXT_CDS <CON_LAST_MODIFIED>
J 0
(15615 -1610);
DISPLAY 0.978723 (15615 -1610);
FORCEPROP 2 LAST CUSTOM_TXT_CDS <XR_PAGE_TITLE>
J 0
(9610 3625);
DISPLAY 0.638298 (9610 3625);
PAINT PINK (9610 3625);
DISPLAY INVISIBLE (9610 3625);
FORCEPROP 1 LAST CUSTOM_TXT_CDS <NAME_2>
J 0
(14325 -1575);
FORCEPROP 1 LAST CUSTOM_TXT_CDS <NAME_1>
J 0
(14325 -1450);
FORCEPROP 1 LAST CUSTOM_TXT_CDS <Q_NUMBER>
J 0
(16097 -1522);
DISPLAY 1.212766 (16097 -1522);
FORCEPROP 1 LAST CUSTOM_TXT_CDS <Q_PROJ>
J 0
(15118 -1523);
DISPLAY 1.212766 (15118 -1523);
FORCEPROP 1 LAST CUSTOM_TXT_CDS <Q_REV>
J 0
(17316 -1522);
DISPLAY 1.212766 (17316 -1522);
FORCEPROP 1 LAST CUSTOM_TXT_CDS <CON_PAGE_NUM> OF <CON_TOTAL_PAGES>
J 0
(17054 -1607);
DISPLAY 0.978723 (17054 -1607);
FORCEPROP 1 LAST Q_TITLE BMC_PHY_BCM54612E 1/2
J 0
(8184 -1524);
DISPLAY 2.446809 (8184 -1524);
PAINT GREEN (8184 -1524);
FORCEPROP 1 LAST COMMENT_BODY TRUE
J 0
(17512 -1638);
DISPLAY 0.978723 (17512 -1638);
PAINT PEACH (17512 -1638);
DISPLAY INVISIBLE (17512 -1638);
FORCEPROP 2 LAST PAGE_BORDER TRUE
J 0
(9610 3625);
DISPLAY 0.638298 (9610 3625);
PAINT PINK (9610 3625);
DISPLAY INVISIBLE (9610 3625);
FORCEPROP 1 LAST CDS_LMAN_SYM_OUTLINE -9475,6775,100,-125
J 0
(17500 -1625);
DISPLAY 0.468085 (17500 -1625);
PAINT GREEN (17500 -1625);
DISPLAY INVISIBLE (17500 -1625);
FORCEPROP 2 LAST CDS_LIB pure_quanta
J 0
(17500 -1625);
DISPLAY INVISIBLE (17500 -1625);
FORCEPROP 2 LAST CDS_XR_PAGE_TITLE CR-18 : @SCM_LIB.SCM(SCH_1):PAGE18
J 0
(9610 3625);
DISPLAY 0.638298 (9610 3625);
PAINT PINK (9610 3625);
DISPLAY INVISIBLE (9610 3625);
QUIT
